Created on vSure / Trilogy - Netlist Compare Summary.

Version 

FTP Site : valor.com
WEB Site : http://www.valor.com 

DATE :  25 Nov 2014
TIME :  14:36:53


     MISMATCH SUMMARY REPORT
     -----------------------

Job  : 14629-1a_200403112      Job  : 14629-1a_200403112
Step : db                      Step : db
Type : CAD                     Type : CURCAD

-----------------------------------------------

 Mismatch Type: shorted


 Total : 0
-----------------------------------------------

 Mismatch Type: broken


 Total : 0
-----------------------------------------------

 Mismatch Type: missing


 Total : 0
-----------------------------------------------

 Mismatch Type: extra


 Total : 0
-----------------------------------------------
